(kicad_pcb
	(version 20260206)
	(generator "pcbnew")
	(generator_version "10.0")
	(general
		(thickness 1.6)
		(legacy_teardrops no)
	)
	(paper "A4")
	(title_block
		(title "9052_F0T_PDB_Converter_Brick_F_V03_1208_1600_OCP.brd")
		(comment 1 "Grand Teton / footprints 168-173 of 578")
	)
	(layers
		(0 "F.Cu" signal "TOP")
		(4 "In1.Cu" signal "GND")
		(6 "In2.Cu" signal "IN1")
		(8 "In3.Cu" signal "GND1")
		(10 "In4.Cu" signal "VCC")
		(12 "In5.Cu" signal "VCC1")
		(14 "In6.Cu" signal "GND2")
		(16 "In7.Cu" signal "IN2")
		(18 "In8.Cu" signal "GND3")
		(2 "B.Cu" signal "BOTTOM")
		(9 "F.Adhes" user "F.Adhesive")
		(11 "B.Adhes" user "B.Adhesive")
		(13 "F.Paste" user "Package Geometry/Pastemask Top")
		(15 "B.Paste" user "Package Geometry/Pastemask Bottom")
		(5 "F.SilkS" user "Ref Des/Silkscreen Top")
		(7 "B.SilkS" user "Ref Des/Silkscreen Bottom")
		(1 "F.Mask" user "Board Geometry/Soldermask Top")
		(3 "B.Mask" user "Board Geometry/Soldermask Bottom")
		(17 "Dwgs.User" user "User.Drawings")
		(19 "Cmts.User" user "User.Comments")
		(21 "Eco1.User" user "User.Eco1")
		(23 "Eco2.User" user "User.Eco2")
		(25 "Edge.Cuts" user "Board Geometry/Outline")
		(27 "Margin" user)
		(31 "F.CrtYd" user "Package Geometry/Place Bound Top")
		(29 "B.CrtYd" user "Package Geometry/Place Bound Bottom")
		(35 "F.Fab" user "Ref Des/Assembly Top")
		(33 "B.Fab" user "Ref Des/Assembly Bottom")
	)
	(footprint ""
		(layer "F.Cu")
		(at 280.39568 -90.282268)
		(property "Reference" "PQ4"
			(at -7.723886 -5.895848 0)
			(unlocked yes)
			(layer "F.SilkS")
			(effects
				(font
					(size 0.7874 0.5842)
					(thickness 0.1524)
				)
				(justify left)
			)
		)
		(property "Value" ""
			(at 0 0 0)
			(layer "F.Fab")
			(effects
				(font
					(size 1.27 1.27)
				)
			)
		)
		(duplicate_pad_numbers_are_jumpers no)
		(fp_line
			(start -7.649972 -4.99999)
			(end -7.649972 -3.3274)
			(stroke
				(width 0.1524)
				(type default)
			)
			(layer "F.SilkS")
		)
		(fp_line
			(start -7.649972 -1.7526)
			(end -7.649972 1.7526)
			(stroke
				(width 0.1524)
				(type default)
			)
			(layer "F.SilkS")
		)
		(fp_line
			(start -7.649972 3.3274)
			(end -7.649972 4.99999)
			(stroke
				(width 0.1524)
				(type default)
			)
			(layer "F.SilkS")
		)
		(fp_line
			(start -7.649972 4.99999)
			(end 5.115814 4.99999)
			(stroke
				(width 0.1524)
				(type default)
			)
			(layer "F.SilkS")
		)
		(fp_line
			(start 5.115814 -4.99999)
			(end -7.649972 -4.99999)
			(stroke
				(width 0.1524)
				(type default)
			)
			(layer "F.SilkS")
		)
		(fp_line
			(start 7.630414 4.99999)
			(end 7.649972 4.99999)
			(stroke
				(width 0.1524)
				(type default)
			)
			(layer "F.SilkS")
		)
		(fp_line
			(start 7.649972 -4.99999)
			(end 7.630414 -4.99999)
			(stroke
				(width 0.1524)
				(type default)
			)
			(layer "F.SilkS")
		)
		(fp_line
			(start 7.649972 4.99999)
			(end 7.649972 -4.99999)
			(stroke
				(width 0.1524)
				(type default)
			)
			(layer "F.SilkS")
		)
		(fp_line
			(start -7.649972 -4.99999)
			(end -7.649972 4.99999)
			(stroke
				(width 0.1)
				(type default)
			)
			(layer "F.Fab")
		)
		(fp_line
			(start -7.649972 4.99999)
			(end 7.649972 4.99999)
			(stroke
				(width 0.1)
				(type default)
			)
			(layer "F.Fab")
		)
		(fp_line
			(start 7.649972 -4.99999)
			(end -7.649972 -4.99999)
			(stroke
				(width 0.1)
				(type default)
			)
			(layer "F.Fab")
		)
		(fp_line
			(start 7.649972 4.99999)
			(end 7.649972 -4.99999)
			(stroke
				(width 0.1)
				(type default)
			)
			(layer "F.Fab")
		)
		(pad "D" smd circle
			(at 2.15011 0)
			(size 0 0)
			(layers "F.Cu" "F.Mask" "F.Paste")
			(net "P52V_HS1_DRAIN_2")
		)
		(pad "G" smd rect
			(at -7.050024 -2.54 270)
			(size 1.3208 3.0988)
			(layers "F.Cu" "F.Mask" "F.Paste")
			(net "P52V_HS1_GATE4")
		)
		(pad "S" smd rect
			(at -7.050024 2.54 270)
			(size 1.3208 3.0988)
			(layers "F.Cu" "F.Mask" "F.Paste")
			(net "P52V_HS")
		)
		(zone
			(layer "F.Cu")
			(hatch none 0.5)
			(connect_pads
				(clearance 0)
			)
			(min_thickness 0.25)
			(keepout
				(tracks not_allowed)
				(vias allowed)
				(pads allowed)
				(copperpour not_allowed)
				(footprints allowed)
			)
			(placement
				(enabled no)
				(sheetname "")
			)
			(fill
				(thermal_gap 0.5)
				(thermal_bridge_width 0.5)
				(island_removal_mode 0)
			)
			(polygon
				(pts
					(xy 285.57728 -95.260668) (xy 272.75028 -95.260668) (xy 272.75028 -93.533468) (xy 274.96008 -93.533468)
					(xy 274.96008 -92.111068) (xy 272.75028 -92.111068) (xy 272.75028 -88.453468) (xy 274.96008 -88.453468)
					(xy 274.96008 -87.031068) (xy 272.75028 -87.031068) (xy 272.75028 -85.303868) (xy 285.57728 -85.303868)
					(xy 285.57728 -86.472268) (xy 279.37968 -86.472268) (xy 279.37968 -94.092268) (xy 285.57728 -94.092268)
				)
			)
		)
	)
	(footprint ""
		(layer "F.Cu")
		(at 177.8254 -14.6812 180)
		(property "Reference" "PC109"
			(at 0 0 180)
			(layer "F.SilkS")
			(hide yes)
			(effects
				(font
					(size 1.27 1.27)
				)
			)
		)
		(property "Value" ""
			(at 0 0 180)
			(layer "F.Fab")
			(effects
				(font
					(size 1.27 1.27)
				)
			)
		)
		(duplicate_pad_numbers_are_jumpers no)
		(fp_line
			(start 0.7874 0.4064)
			(end -0.7874 0.4064)
			(stroke
				(width 0.1524)
				(type default)
			)
			(layer "F.SilkS")
		)
		(fp_line
			(start 0.7874 -0.4064)
			(end 0.7874 0.4064)
			(stroke
				(width 0.1524)
				(type default)
			)
			(layer "F.SilkS")
		)
		(fp_line
			(start -0.7874 0.4064)
			(end -0.7874 -0.4064)
			(stroke
				(width 0.1524)
				(type default)
			)
			(layer "F.SilkS")
		)
		(fp_line
			(start -0.7874 -0.4064)
			(end 0.7874 -0.4064)
			(stroke
				(width 0.1524)
				(type default)
			)
			(layer "F.SilkS")
		)
		(fp_line
			(start 0.67945 0.3048)
			(end 0.120396 0.3048)
			(stroke
				(width 0.1)
				(type default)
			)
			(layer "F.Fab")
		)
		(fp_line
			(start 0.67945 -0.3048)
			(end 0.67945 0.3048)
			(stroke
				(width 0.1)
				(type default)
			)
			(layer "F.Fab")
		)
		(fp_line
			(start 0.12065 -0.2794)
			(end 0.12065 -0.3048)
			(stroke
				(width 0.1)
				(type default)
			)
			(layer "F.Fab")
		)
		(fp_line
			(start 0.12065 -0.3048)
			(end 0.67945 -0.3048)
			(stroke
				(width 0.1)
				(type default)
			)
			(layer "F.Fab")
		)
		(fp_line
			(start 0.120396 0.3048)
			(end 0.120396 0.2794)
			(stroke
				(width 0.1)
				(type default)
			)
			(layer "F.Fab")
		)
		(fp_line
			(start 0.120396 0.2794)
			(end -0.12065 0.2794)
			(stroke
				(width 0.1)
				(type default)
			)
			(layer "F.Fab")
		)
		(fp_line
			(start -0.12065 0.3048)
			(end -0.67945 0.3048)
			(stroke
				(width 0.1)
				(type default)
			)
			(layer "F.Fab")
		)
		(fp_line
			(start -0.12065 0.2794)
			(end -0.12065 0.3048)
			(stroke
				(width 0.1)
				(type default)
			)
			(layer "F.Fab")
		)
		(fp_line
			(start -0.12065 -0.2794)
			(end 0.12065 -0.2794)
			(stroke
				(width 0.1)
				(type default)
			)
			(layer "F.Fab")
		)
		(fp_line
			(start -0.12065 -0.305054)
			(end -0.12065 -0.2794)
			(stroke
				(width 0.1)
				(type default)
			)
			(layer "F.Fab")
		)
		(fp_line
			(start -0.67945 0.3048)
			(end -0.67945 -0.305054)
			(stroke
				(width 0.1)
				(type default)
			)
			(layer "F.Fab")
		)
		(fp_line
			(start -0.67945 -0.305054)
			(end -0.12065 -0.305054)
			(stroke
				(width 0.1)
				(type default)
			)
			(layer "F.Fab")
		)
		(pad "1" smd circle
			(at -0.40005 0 180)
			(size 0 0)
			(layers "F.Cu" "F.Mask" "F.Paste")
			(net "P3V3_AUX_VCC")
		)
		(pad "2" smd circle
			(at 0.40005 0 180)
			(size 0 0)
			(layers "F.Cu" "F.Mask" "F.Paste")
			(net "GND")
		)
	)
	(footprint ""
		(layer "F.Cu")
		(at 45.67936 -55.07482 180)
		(property "Reference" "R5892"
			(at 0 0 180)
			(layer "F.SilkS")
			(hide yes)
			(effects
				(font
					(size 1.27 1.27)
				)
			)
		)
		(property "Value" ""
			(at 0 0 180)
			(layer "F.Fab")
			(effects
				(font
					(size 1.27 1.27)
				)
			)
		)
		(duplicate_pad_numbers_are_jumpers no)
		(fp_line
			(start 0.7874 0.4064)
			(end -0.7874 0.4064)
			(stroke
				(width 0.1524)
				(type default)
			)
			(layer "F.SilkS")
		)
		(fp_line
			(start 0.7874 -0.4064)
			(end 0.7874 0.4064)
			(stroke
				(width 0.1524)
				(type default)
			)
			(layer "F.SilkS")
		)
		(fp_line
			(start -0.7874 0.4064)
			(end -0.7874 -0.4064)
			(stroke
				(width 0.1524)
				(type default)
			)
			(layer "F.SilkS")
		)
		(fp_line
			(start -0.7874 -0.4064)
			(end 0.7874 -0.4064)
			(stroke
				(width 0.1524)
				(type default)
			)
			(layer "F.SilkS")
		)
		(fp_line
			(start 0.67945 0.3048)
			(end 0.120396 0.3048)
			(stroke
				(width 0.1)
				(type default)
			)
			(layer "F.Fab")
		)
		(fp_line
			(start 0.67945 -0.3048)
			(end 0.67945 0.3048)
			(stroke
				(width 0.1)
				(type default)
			)
			(layer "F.Fab")
		)
		(fp_line
			(start 0.12065 -0.2794)
			(end 0.12065 -0.3048)
			(stroke
				(width 0.1)
				(type default)
			)
			(layer "F.Fab")
		)
		(fp_line
			(start 0.12065 -0.3048)
			(end 0.67945 -0.3048)
			(stroke
				(width 0.1)
				(type default)
			)
			(layer "F.Fab")
		)
		(fp_line
			(start 0.120396 0.3048)
			(end 0.120396 0.2794)
			(stroke
				(width 0.1)
				(type default)
			)
			(layer "F.Fab")
		)
		(fp_line
			(start 0.120396 0.2794)
			(end -0.12065 0.2794)
			(stroke
				(width 0.1)
				(type default)
			)
			(layer "F.Fab")
		)
		(fp_line
			(start -0.12065 0.3048)
			(end -0.67945 0.3048)
			(stroke
				(width 0.1)
				(type default)
			)
			(layer "F.Fab")
		)
		(fp_line
			(start -0.12065 0.2794)
			(end -0.12065 0.3048)
			(stroke
				(width 0.1)
				(type default)
			)
			(layer "F.Fab")
		)
		(fp_line
			(start -0.12065 -0.2794)
			(end 0.12065 -0.2794)
			(stroke
				(width 0.1)
				(type default)
			)
			(layer "F.Fab")
		)
		(fp_line
			(start -0.12065 -0.305054)
			(end -0.12065 -0.2794)
			(stroke
				(width 0.1)
				(type default)
			)
			(layer "F.Fab")
		)
		(fp_line
			(start -0.67945 0.3048)
			(end -0.67945 -0.305054)
			(stroke
				(width 0.1)
				(type default)
			)
			(layer "F.Fab")
		)
		(fp_line
			(start -0.67945 -0.305054)
			(end -0.12065 -0.305054)
			(stroke
				(width 0.1)
				(type default)
			)
			(layer "F.Fab")
		)
		(pad "1" smd circle
			(at -0.40005 0 180)
			(size 0 0)
			(layers "F.Cu" "F.Mask" "F.Paste")
			(net "P12V_BRICK_PWRGD")
		)
		(pad "2" smd circle
			(at 0.40005 0 180)
			(size 0 0)
			(layers "F.Cu" "F.Mask" "F.Paste")
			(net "P12V_HPDB_0_EN_R")
		)
	)
	(footprint ""
		(layer "F.Cu")
		(at 139.065 -61.849)
		(property "Reference" "PC29"
			(at 0 0 0)
			(layer "F.SilkS")
			(hide yes)
			(effects
				(font
					(size 1.27 1.27)
				)
			)
		)
		(property "Value" ""
			(at 0 0 0)
			(layer "F.Fab")
			(effects
				(font
					(size 1.27 1.27)
				)
			)
		)
		(duplicate_pad_numbers_are_jumpers no)
		(fp_line
			(start -0.7874 -0.4064)
			(end 0.7874 -0.4064)
			(stroke
				(width 0.1524)
				(type default)
			)
			(layer "F.SilkS")
		)
		(fp_line
			(start -0.7874 0.4064)
			(end -0.7874 -0.4064)
			(stroke
				(width 0.1524)
				(type default)
			)
			(layer "F.SilkS")
		)
		(fp_line
			(start 0.7874 -0.4064)
			(end 0.7874 0.4064)
			(stroke
				(width 0.1524)
				(type default)
			)
			(layer "F.SilkS")
		)
		(fp_line
			(start 0.7874 0.4064)
			(end -0.7874 0.4064)
			(stroke
				(width 0.1524)
				(type default)
			)
			(layer "F.SilkS")
		)
		(fp_line
			(start -0.6858 -0.3048)
			(end -0.1016 -0.3048)
			(stroke
				(width 0.1)
				(type default)
			)
			(layer "F.Fab")
		)
		(fp_line
			(start -0.6858 0.3048)
			(end -0.6858 -0.3048)
			(stroke
				(width 0.1)
				(type default)
			)
			(layer "F.Fab")
		)
		(fp_line
			(start -0.1016 -0.3048)
			(end -0.1016 -0.2794)
			(stroke
				(width 0.1)
				(type default)
			)
			(layer "F.Fab")
		)
		(fp_line
			(start -0.1016 -0.2794)
			(end 0.1016 -0.2794)
			(stroke
				(width 0.1)
				(type default)
			)
			(layer "F.Fab")
		)
		(fp_line
			(start -0.1016 0.2794)
			(end -0.1016 0.3048)
			(stroke
				(width 0.1)
				(type default)
			)
			(layer "F.Fab")
		)
		(fp_line
			(start -0.1016 0.3048)
			(end -0.6858 0.3048)
			(stroke
				(width 0.1)
				(type default)
			)
			(layer "F.Fab")
		)
		(fp_line
			(start 0.1016 -0.3048)
			(end 0.6858 -0.3048)
			(stroke
				(width 0.1)
				(type default)
			)
			(layer "F.Fab")
		)
		(fp_line
			(start 0.1016 -0.2794)
			(end 0.1016 -0.3048)
			(stroke
				(width 0.1)
				(type default)
			)
			(layer "F.Fab")
		)
		(fp_line
			(start 0.1016 0.2794)
			(end -0.1016 0.2794)
			(stroke
				(width 0.1)
				(type default)
			)
			(layer "F.Fab")
		)
		(fp_line
			(start 0.1016 0.3048)
			(end 0.1016 0.2794)
			(stroke
				(width 0.1)
				(type default)
			)
			(layer "F.Fab")
		)
		(fp_line
			(start 0.6858 -0.3048)
			(end 0.6858 0.3048)
			(stroke
				(width 0.1)
				(type default)
			)
			(layer "F.Fab")
		)
		(fp_line
			(start 0.6858 0.3048)
			(end 0.1016 0.3048)
			(stroke
				(width 0.1)
				(type default)
			)
			(layer "F.Fab")
		)
		(pad "1" smd rect
			(at -0.40005 0 180)
			(size 0.4572 0.508)
			(layers "F.Cu" "F.Mask" "F.Paste")
			(net "P12V_BRICK")
		)
		(pad "2" smd rect
			(at 0.40005 0 180)
			(size 0.4572 0.508)
			(layers "F.Cu" "F.Mask" "F.Paste")
			(net "GND")
		)
	)
	(footprint ""
		(layer "F.Cu")
		(at 191.341756 -154.315668 -90)
		(property "Reference" "J12"
			(at -1.259332 -5.773928 90)
			(unlocked yes)
			(layer "F.SilkS")
			(effects
				(font
					(size 0.7874 0.5842)
					(thickness 0.1524)
				)
				(justify left)
			)
		)
		(property "Value" ""
			(at 0 0 270)
			(layer "F.Fab")
			(effects
				(font
					(size 1.27 1.27)
				)
			)
		)
		(duplicate_pad_numbers_are_jumpers no)
		(fp_line
			(start 0 4.011168)
			(end -3.330702 -4.771136)
			(stroke
				(width 0.1524)
				(type default)
			)
			(layer "F.SilkS")
		)
		(fp_line
			(start -3.330702 -4.771136)
			(end 3.330702 -4.771136)
			(stroke
				(width 0.1524)
				(type default)
			)
			(layer "F.SilkS")
		)
		(fp_line
			(start 3.330702 -4.771136)
			(end 0 4.011168)
			(stroke
				(width 0.1524)
				(type default)
			)
			(layer "F.SilkS")
		)
		(fp_line
			(start 0 4.011168)
			(end -3.330702 -4.771136)
			(stroke
				(width 0.1)
				(type default)
			)
			(layer "F.Fab")
		)
		(fp_line
			(start -3.330702 -4.771136)
			(end 3.330702 -4.771136)
			(stroke
				(width 0.1)
				(type default)
			)
			(layer "F.Fab")
		)
		(fp_line
			(start 3.330702 -4.771136)
			(end 0 4.011168)
			(stroke
				(width 0.1)
				(type default)
			)
			(layer "F.Fab")
		)
		(pad "1" thru_hole circle
			(at 0 0 270)
			(size 2.159 2.159)
			(drill 1.7018)
			(layers "*.Cu" "*.Mask")
			(remove_unused_layers no)
			(net "GND3")
			(clearance 0.0254)
			(thermal_gap 0.0254)
		)
		(pad "2" thru_hole circle
			(at -1.27 -3.348736 270)
			(size 2.159 2.159)
			(drill 1.7018)
			(layers "*.Cu" "*.Mask")
			(remove_unused_layers no)
			(net "TDR_SE_50_OHM_IN1")
			(clearance 0.0254)
			(thermal_gap 0.0254)
		)
		(pad "3" thru_hole circle
			(at 1.27 -3.348736 270)
			(size 2.159 2.159)
			(drill 1.7018)
			(layers "*.Cu" "*.Mask")
			(remove_unused_layers no)
			(net "TDR_SE_50_OHM_IN1")
			(clearance 0.0254)
			(thermal_gap 0.0254)
		)
	)
	(footprint ""
		(layer "F.Cu")
		(at 178.57089 -9.32053)
		(property "Reference" "PC110"
			(at 0 0 0)
			(layer "F.SilkS")
			(hide yes)
			(effects
				(font
					(size 1.27 1.27)
				)
			)
		)
		(property "Value" ""
			(at 0 0 0)
			(layer "F.Fab")
			(effects
				(font
					(size 1.27 1.27)
				)
			)
		)
		(duplicate_pad_numbers_are_jumpers no)
		(fp_line
			(start -0.7874 -0.4064)
			(end 0.7874 -0.4064)
			(stroke
				(width 0.1524)
				(type default)
			)
			(layer "F.SilkS")
		)
		(fp_line
			(start -0.7874 0.4064)
			(end -0.7874 -0.4064)
			(stroke
				(width 0.1524)
				(type default)
			)
			(layer "F.SilkS")
		)
		(fp_line
			(start 0.7874 -0.4064)
			(end 0.7874 0.4064)
			(stroke
				(width 0.1524)
				(type default)
			)
			(layer "F.SilkS")
		)
		(fp_line
			(start 0.7874 0.4064)
			(end -0.7874 0.4064)
			(stroke
				(width 0.1524)
				(type default)
			)
			(layer "F.SilkS")
		)
		(fp_line
			(start -0.67945 -0.305054)
			(end -0.12065 -0.305054)
			(stroke
				(width 0.1)
				(type default)
			)
			(layer "F.Fab")
		)
		(fp_line
			(start -0.67945 0.3048)
			(end -0.67945 -0.305054)
			(stroke
				(width 0.1)
				(type default)
			)
			(layer "F.Fab")
		)
		(fp_line
			(start -0.12065 -0.305054)
			(end -0.12065 -0.2794)
			(stroke
				(width 0.1)
				(type default)
			)
			(layer "F.Fab")
		)
		(fp_line
			(start -0.12065 -0.2794)
			(end 0.12065 -0.2794)
			(stroke
				(width 0.1)
				(type default)
			)
			(layer "F.Fab")
		)
		(fp_line
			(start -0.12065 0.2794)
			(end -0.12065 0.3048)
			(stroke
				(width 0.1)
				(type default)
			)
			(layer "F.Fab")
		)
		(fp_line
			(start -0.12065 0.3048)
			(end -0.67945 0.3048)
			(stroke
				(width 0.1)
				(type default)
			)
			(layer "F.Fab")
		)
		(fp_line
			(start 0.120396 0.2794)
			(end -0.12065 0.2794)
			(stroke
				(width 0.1)
				(type default)
			)
			(layer "F.Fab")
		)
		(fp_line
			(start 0.120396 0.3048)
			(end 0.120396 0.2794)
			(stroke
				(width 0.1)
				(type default)
			)
			(layer "F.Fab")
		)
		(fp_line
			(start 0.12065 -0.3048)
			(end 0.67945 -0.3048)
			(stroke
				(width 0.1)
				(type default)
			)
			(layer "F.Fab")
		)
		(fp_line
			(start 0.12065 -0.2794)
			(end 0.12065 -0.3048)
			(stroke
				(width 0.1)
				(type default)
			)
			(layer "F.Fab")
		)
		(fp_line
			(start 0.67945 -0.3048)
			(end 0.67945 0.3048)
			(stroke
				(width 0.1)
				(type default)
			)
			(layer "F.Fab")
		)
		(fp_line
			(start 0.67945 0.3048)
			(end 0.120396 0.3048)
			(stroke
				(width 0.1)
				(type default)
			)
			(layer "F.Fab")
		)
		(pad "1" smd circle
			(at -0.40005 0)
			(size 0 0)
			(layers "F.Cu" "F.Mask" "F.Paste")
			(net "GND")
		)
		(pad "2" smd circle
			(at 0.40005 0)
			(size 0 0)
			(layers "F.Cu" "F.Mask" "F.Paste")
			(net "P3V3_AUX_REF")
		)
	)
)
